# T6G (Grand Teton) — schematic netlist excerpt (pin names and nets, part order shuffled) for the footprints in the layout excerpt that follows; sources: Cadence DE-HDL packaged netlist, KiCad conversion of 04192023_DAF0TMB3IC0_F0TG_MB_C_brd_V02_OCP.brd

R3521  Q_RES  54.9K 1% CHIP  pkg 0402LF  page 248 : A = P3V3_AUX ; B = SMB_2_BMC_GPU_BUF_R_SCL
R3449  Q_RES  100K 1% CHIP  pkg 0402LF  page 128 : A = GPU_FPGA_BOOT_EN ; B = GND

(kicad_pcb
	(version 20260206)
	(generator "pcbnew")
	(generator_version "10.0")
	(general
		(thickness 1.6)
		(legacy_teardrops no)
	)
	(paper "A4")
	(title_block
		(title "04192023_DAF0TMB3IC0_F0TG_MB_C_brd_V02_OCP.brd")
		(comment 1 "Grand Teton / footprints 314-315 of 8354")
	)
	(layers
		(0 "F.Cu" signal "TOP")
		(4 "In1.Cu" signal "GND")
		(6 "In2.Cu" signal "IN1")
		(8 "In3.Cu" signal "GND1")
		(10 "In4.Cu" signal "IN2")
		(12 "In5.Cu" signal "GND2")
		(14 "In6.Cu" signal "IN3")
		(16 "In7.Cu" signal "GND3")
		(18 "In8.Cu" signal "VCC")
		(20 "In9.Cu" signal "VCC1")
		(22 "In10.Cu" signal "GND4")
		(24 "In11.Cu" signal "IN4")
		(26 "In12.Cu" signal "GND5")
		(28 "In13.Cu" signal "IN5")
		(30 "In14.Cu" signal "GND6")
		(32 "In15.Cu" signal "IN6")
		(34 "In16.Cu" signal "GND7")
		(2 "B.Cu" signal "BOTTOM")
		(9 "F.Adhes" user "F.Adhesive")
		(11 "B.Adhes" user "B.Adhesive")
		(13 "F.Paste" user "Package Geometry/Pastemask Top")
		(15 "B.Paste" user "Package Geometry/Pastemask Bottom")
		(5 "F.SilkS" user "Ref Des/Silkscreen Top")
		(7 "B.SilkS" user "Ref Des/Silkscreen Bottom")
		(1 "F.Mask" user "Board Geometry/Soldermask Top")
		(3 "B.Mask" user "Board Geometry/Soldermask Bottom")
		(17 "Dwgs.User" user "User.Drawings")
		(19 "Cmts.User" user "User.Comments")
		(21 "Eco1.User" user "User.Eco1")
		(23 "Eco2.User" user "User.Eco2")
		(25 "Edge.Cuts" user "Board Geometry/Outline")
		(27 "Margin" user)
		(31 "F.CrtYd" user "Package Geometry/Place Bound Top")
		(29 "B.CrtYd" user "Package Geometry/Place Bound Bottom")
		(35 "F.Fab" user "Ref Des/Assembly Top")
		(33 "B.Fab" user "Ref Des/Assembly Bottom")
	)
	(footprint ""
		(layer "F.Cu")
		(at 120.396 -432.054)
		(property "Reference" "R3449"
			(at 0 0 0)
			(layer "F.SilkS")
			(hide yes)
			(effects
				(font
					(size 1.27 1.27)
				)
			)
		)
		(property "Value" ""
			(at 0 0 0)
			(layer "F.Fab")
			(effects
				(font
					(size 1.27 1.27)
				)
			)
		)
		(duplicate_pad_numbers_are_jumpers no)
		(fp_line
			(start -0.7874 -0.4064)
			(end 0.7874 -0.4064)
			(stroke
				(width 0.1524)
				(type default)
			)
			(layer "F.SilkS")
		)
		(fp_line
			(start -0.7874 0.4064)
			(end -0.7874 -0.4064)
			(stroke
				(width 0.1524)
				(type default)
			)
			(layer "F.SilkS")
		)
		(fp_line
			(start 0.7874 -0.4064)
			(end 0.7874 0.4064)
			(stroke
				(width 0.1524)
				(type default)
			)
			(layer "F.SilkS")
		)
		(fp_line
			(start 0.7874 0.4064)
			(end -0.7874 0.4064)
			(stroke
				(width 0.1524)
				(type default)
			)
			(layer "F.SilkS")
		)
		(fp_line
			(start -0.67945 -0.305054)
			(end -0.12065 -0.305054)
			(stroke
				(width 0.1)
				(type default)
			)
			(layer "F.Fab")
		)
		(fp_line
			(start -0.67945 0.3048)
			(end -0.67945 -0.305054)
			(stroke
				(width 0.1)
				(type default)
			)
			(layer "F.Fab")
		)
		(fp_line
			(start -0.12065 -0.305054)
			(end -0.12065 -0.2794)
			(stroke
				(width 0.1)
				(type default)
			)
			(layer "F.Fab")
		)
		(fp_line
			(start -0.12065 -0.2794)
			(end 0.12065 -0.2794)
			(stroke
				(width 0.1)
				(type default)
			)
			(layer "F.Fab")
		)
		(fp_line
			(start -0.12065 0.2794)
			(end -0.12065 0.3048)
			(stroke
				(width 0.1)
				(type default)
			)
			(layer "F.Fab")
		)
		(fp_line
			(start -0.12065 0.3048)
			(end -0.67945 0.3048)
			(stroke
				(width 0.1)
				(type default)
			)
			(layer "F.Fab")
		)
		(fp_line
			(start 0.120396 0.2794)
			(end -0.12065 0.2794)
			(stroke
				(width 0.1)
				(type default)
			)
			(layer "F.Fab")
		)
		(fp_line
			(start 0.120396 0.3048)
			(end 0.120396 0.2794)
			(stroke
				(width 0.1)
				(type default)
			)
			(layer "F.Fab")
		)
		(fp_line
			(start 0.12065 -0.3048)
			(end 0.67945 -0.3048)
			(stroke
				(width 0.1)
				(type default)
			)
			(layer "F.Fab")
		)
		(fp_line
			(start 0.12065 -0.2794)
			(end 0.12065 -0.3048)
			(stroke
				(width 0.1)
				(type default)
			)
			(layer "F.Fab")
		)
		(fp_line
			(start 0.67945 -0.3048)
			(end 0.67945 0.3048)
			(stroke
				(width 0.1)
				(type default)
			)
			(layer "F.Fab")
		)
		(fp_line
			(start 0.67945 0.3048)
			(end 0.120396 0.3048)
			(stroke
				(width 0.1)
				(type default)
			)
			(layer "F.Fab")
		)
		(pad "1" smd circle
			(at -0.40005 0)
			(size 0 0)
			(layers "F.Cu" "F.Mask" "F.Paste")
			(net "GPU_FPGA_BOOT_EN")
		)
		(pad "2" smd circle
			(at 0.40005 0)
			(size 0 0)
			(layers "F.Cu" "F.Mask" "F.Paste")
			(net "GND")
		)
	)
	(footprint ""
		(layer "F.Cu")
		(at 35.881818 -437.449214 180)
		(property "Reference" "R3521"
			(at 0 0 180)
			(layer "F.SilkS")
			(hide yes)
			(effects
				(font
					(size 1.27 1.27)
				)
			)
		)
		(property "Value" ""
			(at 0 0 180)
			(layer "F.Fab")
			(effects
				(font
					(size 1.27 1.27)
				)
			)
		)
		(duplicate_pad_numbers_are_jumpers no)
		(fp_line
			(start 0.7874 0.4064)
			(end -0.7874 0.4064)
			(stroke
				(width 0.1524)
				(type default)
			)
			(layer "F.SilkS")
		)
		(fp_line
			(start 0.7874 -0.4064)
			(end 0.7874 0.4064)
			(stroke
				(width 0.1524)
				(type default)
			)
			(layer "F.SilkS")
		)
		(fp_line
			(start -0.7874 0.4064)
			(end -0.7874 -0.4064)
			(stroke
				(width 0.1524)
				(type default)
			)
			(layer "F.SilkS")
		)
		(fp_line
			(start -0.7874 -0.4064)
			(end 0.7874 -0.4064)
			(stroke
				(width 0.1524)
				(type default)
			)
			(layer "F.SilkS")
		)
		(fp_line
			(start 0.67945 0.3048)
			(end 0.120396 0.3048)
			(stroke
				(width 0.1)
				(type default)
			)
			(layer "F.Fab")
		)
		(fp_line
			(start 0.67945 -0.3048)
			(end 0.67945 0.3048)
			(stroke
				(width 0.1)
				(type default)
			)
			(layer "F.Fab")
		)
		(fp_line
			(start 0.12065 -0.2794)
			(end 0.12065 -0.3048)
			(stroke
				(width 0.1)
				(type default)
			)
			(layer "F.Fab")
		)
		(fp_line
			(start 0.12065 -0.3048)
			(end 0.67945 -0.3048)
			(stroke
				(width 0.1)
				(type default)
			)
			(layer "F.Fab")
		)
		(fp_line
			(start 0.120396 0.3048)
			(end 0.120396 0.2794)
			(stroke
				(width 0.1)
				(type default)
			)
			(layer "F.Fab")
		)
		(fp_line
			(start 0.120396 0.2794)
			(end -0.12065 0.2794)
			(stroke
				(width 0.1)
				(type default)
			)
			(layer "F.Fab")
		)
		(fp_line
			(start -0.12065 0.3048)
			(end -0.67945 0.3048)
			(stroke
				(width 0.1)
				(type default)
			)
			(layer "F.Fab")
		)
		(fp_line
			(start -0.12065 0.2794)
			(end -0.12065 0.3048)
			(stroke
				(width 0.1)
				(type default)
			)
			(layer "F.Fab")
		)
		(fp_line
			(start -0.12065 -0.2794)
			(end 0.12065 -0.2794)
			(stroke
				(width 0.1)
				(type default)
			)
			(layer "F.Fab")
		)
		(fp_line
			(start -0.12065 -0.305054)
			(end -0.12065 -0.2794)
			(stroke
				(width 0.1)
				(type default)
			)
			(layer "F.Fab")
		)
		(fp_line
			(start -0.67945 0.3048)
			(end -0.67945 -0.305054)
			(stroke
				(width 0.1)
				(type default)
			)
			(layer "F.Fab")
		)
		(fp_line
			(start -0.67945 -0.305054)
			(end -0.12065 -0.305054)
			(stroke
				(width 0.1)
				(type default)
			)
			(layer "F.Fab")
		)
		(pad "1" smd circle
			(at -0.40005 0 180)
			(size 0 0)
			(layers "F.Cu" "F.Mask" "F.Paste")
			(net "P3V3_AUX")
		)
		(pad "2" smd circle
			(at 0.40005 0 180)
			(size 0 0)
			(layers "F.Cu" "F.Mask" "F.Paste")
			(net "SMB_2_BMC_GPU_BUF_R_SCL")
		)
	)
)
